# S9S_MB_2U (Grand Teton) — schematic netlist excerpt (pin names and nets, part order shuffled) for the footprints in the layout excerpt that follows; sources: Cadence DE-HDL packaged netlist, KiCad conversion of 03242023_DA0F0TMBIJ0_F0T_Motherboard_J_brd_V01_OCP.brd

PU295  MAX15090BEWIT  MAX15090BEWI+T IC  pkg BGA28_0-5_3-525X2-065  page 192
  ISENSE  = P3V3_E1S_SENSE_0
  VCC  = P3V3_E1S_VCC_0
  IN_A3  = P3V3_AUX
  OUT_A4  = P3V3_E1S_0_R
  IN_A5  = P3V3_AUX
  GATE  = P3V3_E1S_GATE_0
  CDLY  = GND
  CB  = P3V3_E1S_CB_0
  GND_B2  = GND
  IN_B3  = P3V3_AUX
  OUT_B4  = P3V3_E1S_0_R
  IN_B5  = P3V3_AUX
  OUT_B6  = P3V3_E1S_0_R
  \en#\  = GND
  GND_C1  = GND
  GND_C2  = GND
  IN_C3  = P3V3_AUX
  OUT_C4  = P3V3_E1S_0_R
  IN_C5  = P3V3_AUX
  OUT_C6  = P3V3_E1S_0_R
  \fault#\  = P3V3_E1S_FAULT_0
  REG  = P3V3_E1S_REG_0
  UV  = P3V3_E1S_UV_0
  OV  = P3V3_E1S_OV_0
  OUT_D4  = P3V3_E1S_0_R
  IN_D5  = P3V3_AUX
  OUT_D6  = P3V3_E1S_0_R
  PG  = P3V3_E1S_PWRGD_0

(kicad_pcb
	(version 20260206)
	(generator "pcbnew")
	(generator_version "10.0")
	(general
		(thickness 1.6)
		(legacy_teardrops no)
	)
	(paper "A4")
	(title_block
		(title "03242023_DA0F0TMBIJ0_F0T_Motherboard_J_brd_V01_OCP.brd")
		(comment 1 "Grand Teton / footprints 1030-1030 of 6105")
	)
	(layers
		(0 "F.Cu" signal "TOP")
		(4 "In1.Cu" signal "GND")
		(6 "In2.Cu" signal "IN1")
		(8 "In3.Cu" signal "GND1")
		(10 "In4.Cu" signal "IN2")
		(12 "In5.Cu" signal "GND2")
		(14 "In6.Cu" signal "IN3")
		(16 "In7.Cu" signal "GND3")
		(18 "In8.Cu" signal "VCC")
		(20 "In9.Cu" signal "VCC1")
		(22 "In10.Cu" signal "GND4")
		(24 "In11.Cu" signal "IN4")
		(26 "In12.Cu" signal "GND5")
		(28 "In13.Cu" signal "IN5")
		(30 "In14.Cu" signal "GND6")
		(32 "In15.Cu" signal "IN6")
		(34 "In16.Cu" signal "GND7")
		(2 "B.Cu" signal "BOTTOM")
		(9 "F.Adhes" user "F.Adhesive")
		(11 "B.Adhes" user "B.Adhesive")
		(13 "F.Paste" user "Package Geometry/Pastemask Top")
		(15 "B.Paste" user "Package Geometry/Pastemask Bottom")
		(5 "F.SilkS" user "Ref Des/Silkscreen Top")
		(7 "B.SilkS" user "Ref Des/Silkscreen Bottom")
		(1 "F.Mask" user "Board Geometry/Soldermask Top")
		(3 "B.Mask" user "Board Geometry/Soldermask Bottom")
		(17 "Dwgs.User" user "User.Drawings")
		(19 "Cmts.User" user "User.Comments")
		(21 "Eco1.User" user "User.Eco1")
		(23 "Eco2.User" user "User.Eco2")
		(25 "Edge.Cuts" user "Board Geometry/Outline")
		(27 "Margin" user)
		(31 "F.CrtYd" user "Package Geometry/Place Bound Top")
		(29 "B.CrtYd" user "Package Geometry/Place Bound Bottom")
		(35 "F.Fab" user "Ref Des/Assembly Top")
		(33 "B.Fab" user "Ref Des/Assembly Bottom")
	)
	(footprint ""
		(layer "F.Cu")
		(at 221.821502 -70.870318)
		(property "Reference" "PU295"
			(at 4.473448 0.014478 0)
			(unlocked yes)
			(layer "F.SilkS")
			(effects
				(font
					(size 0.7874 0.5842)
					(thickness 0.1524)
				)
				(justify left)
			)
		)
		(property "Value" ""
			(at 0 0 0)
			(layer "F.Fab")
			(effects
				(font
					(size 1.27 1.27)
				)
			)
		)
		(duplicate_pad_numbers_are_jumpers no)
		(fp_line
			(start -1.774952 -1.039876)
			(end -1.774952 1.039876)
			(stroke
				(width 0.1524)
				(type default)
			)
			(layer "F.SilkS")
		)
		(fp_line
			(start -1.774952 1.039876)
			(end 1.774952 1.039876)
			(stroke
				(width 0.1524)
				(type default)
			)
			(layer "F.SilkS")
		)
		(fp_line
			(start 1.774952 -1.039876)
			(end -1.774952 -1.039876)
			(stroke
				(width 0.1524)
				(type default)
			)
			(layer "F.SilkS")
		)
		(fp_line
			(start 1.774952 1.039876)
			(end 1.774952 -1.039876)
			(stroke
				(width 0.1524)
				(type default)
			)
			(layer "F.SilkS")
		)
		(fp_poly
			(pts
				(xy -1.769872 -1.039876) (xy -1.769872 -0.249936) (xy -2.531872 -0.249936) (xy -2.531872 -1.801876)
				(xy -0.999998 -1.801876) (xy -0.999998 -1.039876)
			)
			(stroke
				(width 0)
				(type default)
			)
			(fill yes)
			(layer "F.SilkS")
		)
		(fp_line
			(start -1.769872 -1.039876)
			(end -1.769872 1.039876)
			(stroke
				(width 0.1)
				(type default)
			)
			(layer "F.Fab")
		)
		(fp_line
			(start -1.769872 1.039876)
			(end 1.769872 1.039876)
			(stroke
				(width 0.1)
				(type default)
			)
			(layer "F.Fab")
		)
		(fp_line
			(start 1.769872 -1.039876)
			(end -1.769872 -1.039876)
			(stroke
				(width 0.1)
				(type default)
			)
			(layer "F.Fab")
		)
		(fp_line
			(start 1.769872 1.039876)
			(end 1.769872 -1.039876)
			(stroke
				(width 0.1)
				(type default)
			)
			(layer "F.Fab")
		)
		(fp_poly
			(pts
				(xy -1.769872 -1.039876) (xy -0.999998 -1.039876) (xy -0.999998 -1.801876) (xy -2.531872 -1.801876)
				(xy -2.531872 -0.249936) (xy -1.769872 -0.249936)
			)
			(stroke
				(width 0)
				(type default)
			)
			(fill yes)
			(layer "F.Fab")
		)
		(pad "A1" smd circle
			(at -1.500124 -0.750062)
			(size 0.2286 0.2286)
			(layers "F.Cu" "F.Mask" "F.Paste")
			(net "P3V3_E1S_SENSE_0")
		)
		(pad "A2" smd circle
			(at -0.999998 -0.750062)
			(size 0.2286 0.2286)
			(layers "F.Cu" "F.Mask" "F.Paste")
			(net "P3V3_E1S_VCC_0")
		)
		(pad "A3" smd circle
			(at -0.499872 -0.750062)
			(size 0.2286 0.2286)
			(layers "F.Cu" "F.Mask" "F.Paste")
			(net "P3V3_AUX")
		)
		(pad "A4" smd circle
			(at 0 -0.750062)
			(size 0.2286 0.2286)
			(layers "F.Cu" "F.Mask" "F.Paste")
			(net "P3V3_E1S_0_R")
		)
		(pad "A5" smd circle
			(at 0.499872 -0.750062)
			(size 0.2286 0.2286)
			(layers "F.Cu" "F.Mask" "F.Paste")
			(net "P3V3_AUX")
		)
		(pad "A6" smd circle
			(at 0.999998 -0.750062)
			(size 0.2286 0.2286)
			(layers "F.Cu" "F.Mask" "F.Paste")
			(net "P3V3_E1S_GATE_0")
		)
		(pad "A7" smd circle
			(at 1.500124 -0.750062)
			(size 0.2286 0.2286)
			(layers "F.Cu" "F.Mask" "F.Paste")
			(net "GND")
		)
		(pad "B1" smd circle
			(at -1.500124 -0.249936)
			(size 0.2286 0.2286)
			(layers "F.Cu" "F.Mask" "F.Paste")
			(net "P3V3_E1S_CB_0")
		)
		(pad "B2" smd circle
			(at -0.999998 -0.249936)
			(size 0.2286 0.2286)
			(layers "F.Cu" "F.Mask" "F.Paste")
			(net "GND")
		)
		(pad "B3" smd circle
			(at -0.499872 -0.249936)
			(size 0.2286 0.2286)
			(layers "F.Cu" "F.Mask" "F.Paste")
			(net "P3V3_AUX")
		)
		(pad "B4" smd circle
			(at 0 -0.249936)
			(size 0.2286 0.2286)
			(layers "F.Cu" "F.Mask" "F.Paste")
			(net "P3V3_E1S_0_R")
		)
		(pad "B5" smd circle
			(at 0.499872 -0.249936)
			(size 0.2286 0.2286)
			(layers "F.Cu" "F.Mask" "F.Paste")
			(net "P3V3_AUX")
		)
		(pad "B6" smd circle
			(at 0.999998 -0.249936)
			(size 0.2286 0.2286)
			(layers "F.Cu" "F.Mask" "F.Paste")
			(net "P3V3_E1S_0_R")
		)
		(pad "B7" smd circle
			(at 1.500124 -0.249936)
			(size 0.2286 0.2286)
			(layers "F.Cu" "F.Mask" "F.Paste")
			(net "GND")
		)
		(pad "C1" smd circle
			(at -1.500124 0.249936)
			(size 0.2286 0.2286)
			(layers "F.Cu" "F.Mask" "F.Paste")
			(net "GND")
		)
		(pad "C2" smd circle
			(at -0.999998 0.249936)
			(size 0.2286 0.2286)
			(layers "F.Cu" "F.Mask" "F.Paste")
			(net "GND")
		)
		(pad "C3" smd circle
			(at -0.499872 0.249936)
			(size 0.2286 0.2286)
			(layers "F.Cu" "F.Mask" "F.Paste")
			(net "P3V3_AUX")
		)
		(pad "C4" smd circle
			(at 0 0.249936)
			(size 0.2286 0.2286)
			(layers "F.Cu" "F.Mask" "F.Paste")
			(net "P3V3_E1S_0_R")
		)
		(pad "C5" smd circle
			(at 0.499872 0.249936)
			(size 0.2286 0.2286)
			(layers "F.Cu" "F.Mask" "F.Paste")
			(net "P3V3_AUX")
		)
		(pad "C6" smd circle
			(at 0.999998 0.249936)
			(size 0.2286 0.2286)
			(layers "F.Cu" "F.Mask" "F.Paste")
			(net "P3V3_E1S_0_R")
		)
		(pad "C7" smd circle
			(at 1.500124 0.249936)
			(size 0.2286 0.2286)
			(layers "F.Cu" "F.Mask" "F.Paste")
			(net "P3V3_E1S_FAULT_0")
		)
		(pad "D1" smd circle
			(at -1.500124 0.750062)
			(size 0.2286 0.2286)
			(layers "F.Cu" "F.Mask" "F.Paste")
			(net "P3V3_E1S_REG_0")
		)
		(pad "D2" smd circle
			(at -0.999998 0.750062)
			(size 0.2286 0.2286)
			(layers "F.Cu" "F.Mask" "F.Paste")
			(net "P3V3_E1S_UV_0")
		)
		(pad "D3" smd circle
			(at -0.499872 0.750062)
			(size 0.2286 0.2286)
			(layers "F.Cu" "F.Mask" "F.Paste")
			(net "P3V3_E1S_OV_0")
		)
		(pad "D4" smd circle
			(at 0 0.750062)
			(size 0.2286 0.2286)
			(layers "F.Cu" "F.Mask" "F.Paste")
			(net "P3V3_E1S_0_R")
		)
		(pad "D5" smd circle
			(at 0.499872 0.750062)
			(size 0.2286 0.2286)
			(layers "F.Cu" "F.Mask" "F.Paste")
			(net "P3V3_AUX")
		)
		(pad "D6" smd circle
			(at 0.999998 0.750062)
			(size 0.2286 0.2286)
			(layers "F.Cu" "F.Mask" "F.Paste")
			(net "P3V3_E1S_0_R")
		)
		(pad "D7" smd circle
			(at 1.500124 0.750062)
			(size 0.2286 0.2286)
			(layers "F.Cu" "F.Mask" "F.Paste")
			(net "P3V3_E1S_PWRGD_0")
		)
	)
)
